(kicad_pcb
	(version 20260206)
	(generator "pcbnew")
	(generator_version "10.0")
	(general
		(thickness 1.6)
		(legacy_teardrops no)
	)
	(paper "A4")
	(title_block
		(title "15969-1a.1015WZS0858.brd")
		(comment 1 "Tioga Pass / footprints 145-149 of 295")
	)
	(layers
		(0 "F.Cu" signal "TOP")
		(4 "In1.Cu" signal "L2GND")
		(6 "In2.Cu" signal "L3")
		(8 "In3.Cu" signal "L4")
		(10 "In4.Cu" signal "L5GND")
		(2 "B.Cu" signal "BOTTOM")
		(9 "F.Adhes" user "F.Adhesive")
		(11 "B.Adhes" user "B.Adhesive")
		(13 "F.Paste" user "Package Geometry/Pastemask Top")
		(15 "B.Paste" user "Package Geometry/Pastemask Bottom")
		(5 "F.SilkS" user "Ref Des/Silkscreen Top")
		(7 "B.SilkS" user "Ref Des/Silkscreen Bottom")
		(1 "F.Mask" user "Board Geometry/Soldermask Top")
		(3 "B.Mask" user "Board Geometry/Soldermask Bottom")
		(17 "Dwgs.User" user "User.Drawings")
		(19 "Cmts.User" user "User.Comments")
		(21 "Eco1.User" user "User.Eco1")
		(23 "Eco2.User" user "User.Eco2")
		(25 "Edge.Cuts" user "Board Geometry/Outline")
		(27 "Margin" user)
		(31 "F.CrtYd" user "Package Geometry/Place Bound Top")
		(29 "B.CrtYd" user "Package Geometry/Place Bound Bottom")
		(35 "F.Fab" user "Ref Des/Assembly Top")
		(33 "B.Fab" user "Ref Des/Assembly Bottom")
	)
	(footprint ""
		(layer "F.Cu")
		(at 28.6004 -16.7894 180)
		(property "Reference" "C14"
			(at 0 0 180)
			(layer "F.SilkS")
			(hide yes)
			(effects
				(font
					(size 1.27 1.27)
				)
			)
		)
		(property "Value" "SCD1U25V3KX-GP"
			(at 0 -2.8194 180)
			(unlocked yes)
			(layer "F.Fab")
			(hide yes)
			(effects
				(font
					(size 1.016 1.016)
					(thickness 0.1524)
				)
			)
		)
		(property "Device Type" "C603H36"
			(at 0 -4.3434 180)
			(unlocked yes)
			(layer "F.Fab")
			(hide yes)
			(effects
				(font
					(size 1.016 1.016)
					(thickness 0.1524)
				)
			)
		)
		(duplicate_pad_numbers_are_jumpers no)
		(fp_line
			(start 0.508 0)
			(end -0.508 0)
			(stroke
				(width 0.2032)
				(type default)
			)
			(layer "F.SilkS")
		)
		(fp_rect
			(start -0.5842 1.3335)
			(end 0.5842 -1.3335)
			(stroke
				(width 0)
				(type default)
			)
			(fill no)
			(layer "F.CrtYd")
		)
		(fp_rect
			(start -0.5842 1.3335)
			(end 0.5842 -1.3335)
			(stroke
				(width 0)
				(type default)
			)
			(fill no)
			(layer "F.Fab")
		)
		(pad "1" smd custom
			(at 0 -0.762 180)
			(size 0.2159 0.2159)
			(layers "F.Cu" "F.Mask" "F.Paste")
			(net "P12V_SLOT2")
			(options
				(clearance outline)
				(anchor circle)
			)
			(primitives
				(gr_poly
					(pts
						(arc
							(start -0.3302 -0.4318)
							(mid -0.402042 -0.402042)
							(end -0.4318 -0.3302)
						)
						(arc
							(start -0.4318 0.3302)
							(mid -0.402042 0.402042)
							(end -0.3302 0.4318)
						)
						(arc
							(start 0.3302 0.4318)
							(mid 0.402042 0.402042)
							(end 0.4318 0.3302)
						)
						(arc
							(start 0.4318 -0.3302)
							(mid 0.402042 -0.402042)
							(end 0.3302 -0.4318)
						)
					)
					(width 0)
					(fill yes)
				)
			)
		)
		(pad "2" smd custom
			(at 0 0.762 180)
			(size 0.2159 0.2159)
			(layers "F.Cu" "F.Mask" "F.Paste")
			(net "GND")
			(options
				(clearance outline)
				(anchor circle)
			)
			(primitives
				(gr_poly
					(pts
						(arc
							(start -0.3302 -0.4318)
							(mid -0.402042 -0.402042)
							(end -0.4318 -0.3302)
						)
						(arc
							(start -0.4318 0.3302)
							(mid -0.402042 0.402042)
							(end -0.3302 0.4318)
						)
						(arc
							(start 0.3302 0.4318)
							(mid 0.402042 0.402042)
							(end 0.4318 0.3302)
						)
						(arc
							(start 0.4318 -0.3302)
							(mid 0.402042 -0.402042)
							(end 0.3302 -0.4318)
						)
					)
					(width 0)
					(fill yes)
				)
			)
		)
	)
	(footprint ""
		(layer "F.Cu")
		(at 38.6969 -0.0635 90)
		(property "Reference" "C17"
			(at 0 0 90)
			(layer "F.SilkS")
			(hide yes)
			(effects
				(font
					(size 1.27 1.27)
				)
			)
		)
		(property "Value" "SCD1U16V2KX-3GP"
			(at 1.1811 -2.7051 90)
			(unlocked yes)
			(layer "F.Fab")
			(hide yes)
			(effects
				(font
					(size 1.016 1.016)
					(thickness 0.1524)
				)
			)
		)
		(property "Device Type" "C402H22"
			(at 1.1811 -4.2291 90)
			(unlocked yes)
			(layer "F.Fab")
			(hide yes)
			(effects
				(font
					(size 1.016 1.016)
					(thickness 0.1524)
				)
			)
		)
		(duplicate_pad_numbers_are_jumpers no)
		(fp_rect
			(start -0.4318 0.9525)
			(end 0.4318 -0.9525)
			(stroke
				(width 0)
				(type default)
			)
			(fill no)
			(layer "F.CrtYd")
		)
		(fp_rect
			(start -0.4318 0.9525)
			(end 0.4318 -0.9525)
			(stroke
				(width 0)
				(type default)
			)
			(fill no)
			(layer "F.Fab")
		)
		(pad "1" smd custom
			(at 0 -0.4445 90)
			(size 0.1524 0.1524)
			(layers "F.Cu" "F.Mask" "F.Paste")
			(net "P3V3")
			(options
				(clearance outline)
				(anchor circle)
			)
			(primitives
				(gr_poly
					(pts
						(arc
							(start 0.3048 -0.2032)
							(mid 0.275042 -0.275042)
							(end 0.2032 -0.3048)
						)
						(arc
							(start -0.2032 -0.3048)
							(mid -0.275042 -0.275042)
							(end -0.3048 -0.2032)
						)
						(arc
							(start -0.3048 0.2032)
							(mid -0.275042 0.275042)
							(end -0.2032 0.3048)
						)
						(arc
							(start 0.2032 0.3048)
							(mid 0.275042 0.275042)
							(end 0.3048 0.2032)
						)
					)
					(width 0)
					(fill yes)
				)
			)
		)
		(pad "2" smd custom
			(at 0 0.4445 90)
			(size 0.1524 0.1524)
			(layers "F.Cu" "F.Mask" "F.Paste")
			(net "GND")
			(options
				(clearance outline)
				(anchor circle)
			)
			(primitives
				(gr_poly
					(pts
						(arc
							(start 0.3048 -0.2032)
							(mid 0.275042 -0.275042)
							(end 0.2032 -0.3048)
						)
						(arc
							(start -0.2032 -0.3048)
							(mid -0.275042 -0.275042)
							(end -0.3048 -0.2032)
						)
						(arc
							(start -0.3048 0.2032)
							(mid -0.275042 0.275042)
							(end -0.2032 0.3048)
						)
						(arc
							(start 0.2032 0.3048)
							(mid 0.275042 0.275042)
							(end 0.3048 0.2032)
						)
					)
					(width 0)
					(fill yes)
				)
			)
		)
	)
	(footprint ""
		(layer "F.Cu")
		(at 27.3812 -16.764 180)
		(property "Reference" "C16"
			(at 0 0 180)
			(layer "F.SilkS")
			(hide yes)
			(effects
				(font
					(size 1.27 1.27)
				)
			)
		)
		(property "Value" "SCD1U25V3KX-GP"
			(at 0 -2.8194 180)
			(unlocked yes)
			(layer "F.Fab")
			(hide yes)
			(effects
				(font
					(size 1.016 1.016)
					(thickness 0.1524)
				)
			)
		)
		(property "Device Type" "C603H36"
			(at 0 -4.3434 180)
			(unlocked yes)
			(layer "F.Fab")
			(hide yes)
			(effects
				(font
					(size 1.016 1.016)
					(thickness 0.1524)
				)
			)
		)
		(duplicate_pad_numbers_are_jumpers no)
		(fp_line
			(start 0.508 0)
			(end -0.508 0)
			(stroke
				(width 0.2032)
				(type default)
			)
			(layer "F.SilkS")
		)
		(fp_rect
			(start -0.5842 1.3335)
			(end 0.5842 -1.3335)
			(stroke
				(width 0)
				(type default)
			)
			(fill no)
			(layer "F.CrtYd")
		)
		(fp_rect
			(start -0.5842 1.3335)
			(end 0.5842 -1.3335)
			(stroke
				(width 0)
				(type default)
			)
			(fill no)
			(layer "F.Fab")
		)
		(pad "1" smd custom
			(at 0 -0.762 180)
			(size 0.2159 0.2159)
			(layers "F.Cu" "F.Mask" "F.Paste")
			(net "P12V_SLOT2")
			(options
				(clearance outline)
				(anchor circle)
			)
			(primitives
				(gr_poly
					(pts
						(arc
							(start -0.3302 -0.4318)
							(mid -0.402042 -0.402042)
							(end -0.4318 -0.3302)
						)
						(arc
							(start -0.4318 0.3302)
							(mid -0.402042 0.402042)
							(end -0.3302 0.4318)
						)
						(arc
							(start 0.3302 0.4318)
							(mid 0.402042 0.402042)
							(end 0.4318 0.3302)
						)
						(arc
							(start 0.4318 -0.3302)
							(mid 0.402042 -0.402042)
							(end 0.3302 -0.4318)
						)
					)
					(width 0)
					(fill yes)
				)
			)
		)
		(pad "2" smd custom
			(at 0 0.762 180)
			(size 0.2159 0.2159)
			(layers "F.Cu" "F.Mask" "F.Paste")
			(net "GND")
			(options
				(clearance outline)
				(anchor circle)
			)
			(primitives
				(gr_poly
					(pts
						(arc
							(start -0.3302 -0.4318)
							(mid -0.402042 -0.402042)
							(end -0.4318 -0.3302)
						)
						(arc
							(start -0.4318 0.3302)
							(mid -0.402042 0.402042)
							(end -0.3302 0.4318)
						)
						(arc
							(start 0.3302 0.4318)
							(mid 0.402042 0.402042)
							(end 0.4318 0.3302)
						)
						(arc
							(start 0.4318 -0.3302)
							(mid 0.402042 -0.402042)
							(end 0.3302 -0.4318)
						)
					)
					(width 0)
					(fill yes)
				)
			)
		)
	)
	(footprint ""
		(layer "F.Cu")
		(at 131.7498 -10.4394 90)
		(property "Reference" "R123"
			(at 0 0 90)
			(layer "F.SilkS")
			(hide yes)
			(effects
				(font
					(size 1.27 1.27)
				)
			)
		)
		(property "Value" "10KR2F-2-GP"
			(at 0.064008 -3.993896 90)
			(unlocked yes)
			(layer "F.Fab")
			(hide yes)
			(effects
				(font
					(size 1.016 1.016)
					(thickness 0.1524)
				)
			)
		)
		(property "Device Type" "R402H16"
			(at 0.064008 -5.517896 90)
			(unlocked yes)
			(layer "F.Fab")
			(hide yes)
			(effects
				(font
					(size 1.016 1.016)
					(thickness 0.1524)
				)
			)
		)
		(duplicate_pad_numbers_are_jumpers no)
		(fp_line
			(start 0.508 -0.9398)
			(end -0.508 -0.9398)
			(stroke
				(width 0.1524)
				(type default)
			)
			(layer "F.SilkS")
		)
		(fp_line
			(start -0.508 -0.9398)
			(end -0.508 0.9398)
			(stroke
				(width 0.1524)
				(type default)
			)
			(layer "F.SilkS")
		)
		(fp_rect
			(start -0.508 0.9398)
			(end 0.508 -0.9398)
			(stroke
				(width 0)
				(type default)
			)
			(fill no)
			(layer "F.CrtYd")
		)
		(fp_rect
			(start -0.508 0.9398)
			(end 0.508 -0.9398)
			(stroke
				(width 0)
				(type default)
			)
			(fill no)
			(layer "F.Fab")
		)
		(pad "1" smd custom
			(at 0 -0.4445 90)
			(size 0.1397 0.1397)
			(layers "F.Cu" "F.Mask" "F.Paste")
			(net "GPIO_B_IO1_3")
			(options
				(clearance outline)
				(anchor circle)
			)
			(primitives
				(gr_poly
					(pts
						(arc
							(start -0.1778 -0.2794)
							(mid -0.249642 -0.249642)
							(end -0.2794 -0.1778)
						)
						(arc
							(start -0.2794 0.1778)
							(mid -0.249642 0.249642)
							(end -0.1778 0.2794)
						)
						(arc
							(start 0.1778 0.2794)
							(mid 0.249642 0.249642)
							(end 0.2794 0.1778)
						)
						(arc
							(start 0.2794 -0.1778)
							(mid 0.249642 -0.249642)
							(end 0.1778 -0.2794)
						)
					)
					(width 0)
					(fill yes)
				)
			)
		)
		(pad "2" smd custom
			(at 0 0.4445 90)
			(size 0.1397 0.1397)
			(layers "F.Cu" "F.Mask" "F.Paste")
			(net "GND")
			(options
				(clearance outline)
				(anchor circle)
			)
			(primitives
				(gr_poly
					(pts
						(arc
							(start -0.1778 -0.2794)
							(mid -0.249642 -0.249642)
							(end -0.2794 -0.1778)
						)
						(arc
							(start -0.2794 0.1778)
							(mid -0.249642 0.249642)
							(end -0.1778 0.2794)
						)
						(arc
							(start 0.1778 0.2794)
							(mid 0.249642 0.249642)
							(end 0.2794 0.1778)
						)
						(arc
							(start 0.2794 -0.1778)
							(mid 0.249642 -0.249642)
							(end 0.1778 -0.2794)
						)
					)
					(width 0)
					(fill yes)
				)
			)
		)
	)
	(footprint ""
		(layer "F.Cu")
		(at 23.1394 -13.7922 90)
		(property "Reference" "PC1"
			(at 0 0 90)
			(layer "F.SilkS")
			(hide yes)
			(effects
				(font
					(size 1.27 1.27)
				)
			)
		)
		(property "Value" "SC22U16V5MX-4-GP"
			(at -0.0762 -6.1214 90)
			(unlocked yes)
			(layer "F.Fab")
			(hide yes)
			(effects
				(font
					(size 1.016 1.016)
					(thickness 0.1524)
				)
			)
		)
		(property "Device Type" "C805H58"
			(at -0.0762 -8.1534 90)
			(unlocked yes)
			(layer "F.Fab")
			(hide yes)
			(effects
				(font
					(size 1.016 1.016)
					(thickness 0.1524)
				)
			)
		)
		(duplicate_pad_numbers_are_jumpers no)
		(fp_line
			(start 0.635 0)
			(end -0.635 0)
			(stroke
				(width 0.508)
				(type default)
			)
			(layer "F.SilkS")
		)
		(fp_rect
			(start -0.9652 1.778)
			(end 0.9652 -1.778)
			(stroke
				(width 0)
				(type default)
			)
			(fill no)
			(layer "F.CrtYd")
		)
		(fp_poly
			(pts
				(xy -0.9652 -1.778) (xy 0.9652 -1.778) (xy 0.9652 1.778) (xy -0.9652 1.778)
			)
			(stroke
				(width 0)
				(type default)
			)
			(fill no)
			(layer "F.Fab")
		)
		(pad "1" smd rect
			(at 0 -0.9652 90)
			(size 1.397 1.143)
			(layers "F.Cu" "F.Mask" "F.Paste")
			(net "P3V3_VIN")
		)
		(pad "2" smd rect
			(at 0 0.9652 90)
			(size 1.397 1.143)
			(layers "F.Cu" "F.Mask" "F.Paste")
			(net "GND")
		)
	)
)
